FILE_TYPE = CONNECTIVITY;
{Allegro Design Entry HDL 17.2-2016 S081 (4005846) 1/11/2022}
"PAGE_NUMBER" = 275;
0"NC";
1"P5V\g";
2"P3V3\g";
3"P5V\g";
4"P3V3\g";
5"SW_P12V_PVCCFA_EHV_FIVRA_CPU1_L\g";
6"SW_P12V_PVCCFA_EHV_FIVRA_CPU1_R\g";
7"PVCCFA_EHV_FIVRA_CPU1\g";
8"PVCCFA_EHV_FIVRA_CPU1\g";
9"P12V_AUX\g";
10"PVCCFA_EHV_FIVRA_CPU1\g";
11"SW_P12V_PVCCFA_EHV_FIVRA_CPU1_L\g";
12"GND\g";
13"GND\g";
14"GND\g";
15"GND\g";
16"GND\g";
17"GND\g";
18"GND\g";
19"GND\g";
20"GND\g";
21"GND\g";
22"GND\g";
23"GND\g";
24"GND\g";
25"GND\g";
26"GND\g";
27"GND\g";
28"GND\g";
29"SW_PVCCFA_EHV_FIVRA_CPU1_BOOTR1";
30"SW_PVCCFA_EHV_FIVRA_CPU1_SW1";
31"PVCCFA_EHV_FIVRA_CPU1_VOS1";
32"SW_PVCCFA_EHV_FIVRA_CPU1_BOOT1_R";
33"SW_PVCCFA_EHV_FIVRA_CPU1_BOOT1";
34"SW_PVCCFA_EHV_FIVRA_CPU1_SW2";
35"SW_PVCCFA_EHV_FIVRA_CPU1_BOOTR2";
36"SW_PVCCFA_EHV_FIVRA_CPU1_BOOT2_R";
37"PVCCFA_EHV_FIVRA_CPU1_VOS2";
38"SW_PVCCFA_EHV_FIVRA_CPU1_BOOT2";
39"PVCCFA_EHV_FIVRA_CPU1_PVCC1";
40"PVCCFA_EHV_FIVRA_CPU1_VDD1"CDS_PHYS_NET_NAME"PVCCFA_EHV_FIVRA_CPU1_VDD1";
41"PVCCIN_CPU1_VREF"CDS_PHYS_NET_NAME"PVCCIN_CPU1_VREF";
42"PVCCFA_EHV_FIVRA_CPU1_BTSEN";
43"PVCCFA_EHV_FIVRA_CPU1_PWM1";
44"PVCCFA_EHV_FIVRA_CPU1_IMON1";
45"PVCCFA_EHV_FIVRA_CPU1_LSET1";
46"PVCCFA_EHV_FIVRA_CPU1_PVCC2";
47"PVCCFA_EHV_FIVRA_CPU1_VDD2"CDS_PHYS_NET_NAME"PVCCFA_EHV_FIVRA_CPU1_VDD2";
48"PVCCFA_EHV_FIVRA_CPU1_IMON2";
49"PVCCIN_CPU1_VREF"CDS_PHYS_NET_NAME"PVCCIN_CPU1_VREF";
50"PVCCFA_EHV_FIVRA_CPU1_PWM2";
51"PVCCFA_EHV_FIVRA_CPU1_BTSEN";
52"PVCCFA_EHV_FIVRA_CPU1_LSET2";
%"UNIVERSAL_GND"
"1","(-10750,1150)","0","logical_power","I1";
;
HDL_POWER"GND"
CDS_LIB"logical_power";
"A"12;
%"UNIVERSAL_GND"
"1","(-10250,2075)","0","logical_power","I10";
;
HDL_POWER"GND"
CDS_LIB"logical_power";
"A"14;
%"Q_CAP"
"1","(-10250,2325)","0","pure_quanta","I11";
;
PART_NUMBER"CH5222KEB01"
MATERIAL"X6S"
TOLERANCE"10%"
VALUE"2.2UF"
VOLTAGE"10V"
PACK_TYPE"C0402"
LOCATION"PC396"
CDS_LIB"pure_quanta"
LOCATION"PC396"
$SEC"1"
CDS_SEC"1";
"B"
$PN"2"14;
"A"
$PN"1"47;
%"Q_RES"
"2","(-10250,2725)","0","pure_quanta","I12";
;
PART_NUMBER"CS-2202FB01"
VALUE"2.2"
TOLERANCE"1%"
WATTAGE"1/16W"
MATERIAL"CHIP"
PACK_TYPE"0402LF"
LOCATION"PR227"
CDS_LIB"pure_quanta"
LOCATION"PR227"
$SEC"1"
CDS_SEC"1";
"A"
$PN"1"46;
"B"
$PN"2"47;
%"Q_RES"
"2","(-10775,3375)","0","pure_quanta","I13";
;
PART_NUMBER"CS00002JB13"
MATERIAL"CHIP"
TOLERANCE"5%"
VALUE"0"
PACK_TYPE"0402LF"
WATTAGE"1/16W"
LOCATION"PR702"
CDS_LIB"pure_quanta"
$SEC"1"
CDS_SEC"1";
"A"
$PN"1"1;
"B"
$PN"2"46;
%"VCC15"
"1","(-10775,3600)","0","logical_power","I14";
;
HDL_POWER"P5V"
CDS_LIB"logical_power";
"A"1;
%"UNIVERSAL_GND"
"1","(-9725,2475)","0","logical_power","I15";
;
HDL_POWER"GND"
CDS_LIB"logical_power";
"A"15;
%"Q_CAP"
"1","(-9725,2725)","0","pure_quanta","I16";
;
PART_NUMBER"CH5222KEB01"
MATERIAL"X6S"
TOLERANCE"10%"
VALUE"2.2UF"
VOLTAGE"10V"
PACK_TYPE"C0402"
LOCATION"PC1243_P1_2"
CDS_LIB"pure_quanta"
$SEC"1"
CDS_SEC"1";
"B"
$PN"2"15;
"A"
$PN"1"46;
%"Q_RES"
"2","(-10125,3375)","0","pure_quanta","I17";
;
PART_NUMBER"CS00002JB13"
PACK_TYPE"0402LF"
MATERIAL"EMPTY"
VALUE"0"
TOLERANCE"5%"
WATTAGE"1/16W"
LOCATION"PR704"
CDS_LIB"pure_quanta"
$SEC"1"
CDS_SEC"1";
"A"
$PN"1"2;
"B"
$PN"2"46;
%"VCC15"
"1","(-10125,3600)","0","logical_power","I18";
;
HDL_POWER"P3V3"
CDS_LIB"logical_power";
"A"2;
%"UNIVERSAL_GND"
"1","(-10725,3950)","0","logical_power","I19";
;
HDL_POWER"GND"
CDS_LIB"logical_power";
"A"16;
%"Q_RES"
"2","(-10750,1375)","2","pure_quanta","I2";
;
PART_NUMBER"CS28872FB01"
WATTAGE"1/16W"
MATERIAL"EMPTY"
TOLERANCE"1%"
VALUE"8.87K"
PACK_TYPE"0402LF"
LOCATION"PR224"
CDS_LIB"pure_quanta"
LOCATION"PR224"
$SEC"1"
CDS_SEC"1";
"A"
$PN"1"52;
"B"
$PN"2"12;
%"Q_RES"
"2","(-10725,4175)","2","pure_quanta","I20";
;
PART_NUMBER"CS28872FB01"
MATERIAL"EMPTY"
WATTAGE"1/16W"
TOLERANCE"1%"
VALUE"8.87K"
PACK_TYPE"0402LF"
LOCATION"PR225"
CDS_LIB"pure_quanta"
LOCATION"PR225"
$SEC"1"
CDS_SEC"1";
"A"
$PN"1"45;
"B"
$PN"2"16;
%"UNIVERSAL_GND"
"1","(-10800,4400)","0","logical_power","I21";
;
HDL_POWER"GND"
CDS_LIB"logical_power";
"A"17;
%"UNIVERSAL_GND"
"1","(-10250,4875)","0","logical_power","I26";
;
HDL_POWER"GND"
CDS_LIB"logical_power";
"A"18;
%"Q_CAP"
"1","(-10250,5125)","0","pure_quanta","I27";
;
PART_NUMBER"CH5222KEB01"
MATERIAL"X6S"
TOLERANCE"10%"
VALUE"2.2UF"
VOLTAGE"10V"
PACK_TYPE"C0402"
LOCATION"PC395"
CDS_LIB"pure_quanta"
LOCATION"PC395"
$SEC"1"
CDS_SEC"1";
"B"
$PN"2"18;
"A"
$PN"1"40;
%"Q_RES"
"2","(-10250,5525)","0","pure_quanta","I28";
;
PART_NUMBER"CS-2202FB01"
WATTAGE"1/16W"
MATERIAL"CHIP"
TOLERANCE"1%"
VALUE"2.2"
PACK_TYPE"0402LF"
LOCATION"PR226"
CDS_LIB"pure_quanta"
LOCATION"PR226"
$SEC"1"
CDS_SEC"1";
"A"
$PN"1"39;
"B"
$PN"2"40;
%"Q_CAP"
"2","(-9975,4475)","0","pure_quanta","I29";
;
PART_NUMBER"CH4104K1B00"
TOLERANCE"10%"
PACK_TYPE"0402"
MATERIAL"X7R"
VOLTAGE"25V"
VALUE"0.1UF"
LOCATION"PC1367"
CDS_LIB"pure_quanta"
$SEC"1"
CDS_SEC"1";
"A"
$PN"1"17;
"B"
$PN"2"41;
%"UNIVERSAL_GND"
"1","(-10800,1600)","0","logical_power","I3";
;
HDL_POWER"GND"
CDS_LIB"logical_power";
"A"13;
%"UNIVERSAL_GND"
"1","(-9725,5275)","0","logical_power","I30";
;
HDL_POWER"GND"
CDS_LIB"logical_power";
"A"19;
%"Q_CAP"
"1","(-9725,5525)","0","pure_quanta","I31";
;
PART_NUMBER"CH5222KEB01"
VOLTAGE"10V"
VALUE"2.2UF"
MATERIAL"X6S"
TOLERANCE"10%"
PACK_TYPE"C0402"
LOCATION"PC1242_P1_1"
CDS_LIB"pure_quanta"
$SEC"1"
CDS_SEC"1";
"B"
$PN"2"19;
"A"
$PN"1"39;
%"Q_RES"
"2","(-10775,6175)","0","pure_quanta","I32";
;
PART_NUMBER"CS00002JB13"
WATTAGE"1/16W"
MATERIAL"CHIP"
TOLERANCE"5%"
VALUE"0"
PACK_TYPE"0402LF"
LOCATION"PR701"
CDS_LIB"pure_quanta"
$SEC"1"
CDS_SEC"1";
"A"
$PN"1"3;
"B"
$PN"2"39;
%"VCC15"
"1","(-10775,6400)","0","logical_power","I33";
;
HDL_POWER"P5V"
CDS_LIB"logical_power";
"A"3;
%"Q_RES"
"2","(-10125,6175)","0","pure_quanta","I34";
;
PART_NUMBER"CS00002JB13"
MATERIAL"EMPTY"
PACK_TYPE"0402LF"
TOLERANCE"5%"
WATTAGE"1/16W"
VALUE"0"
LOCATION"PR703"
CDS_LIB"pure_quanta"
$SEC"1"
CDS_SEC"1";
"A"
$PN"1"4;
"B"
$PN"2"39;
%"VCC15"
"1","(-10125,6400)","0","logical_power","I35";
;
HDL_POWER"P3V3"
CDS_LIB"logical_power";
"A"4;
%"UNIVERSAL_GND"
"1","(-8075,1150)","0","logical_power","I36";
;
HDL_POWER"GND"
CDS_LIB"logical_power";
"A"20;
%"Q_CAP"
"1","(-7925,2775)","0","pure_quanta","I37";
;
PART_NUMBER"TMP_QCH2336K1B12"
VOLTAGE"50V"
PACK_TYPE"0402"
MATERIAL"X7R"
VALUE"3300PF"
TOLERANCE"10%"
LOCATION"PC398_P1_2"
CDS_LIB"pure_quanta"
LOCATION"PC398_P1_2"
$SEC"1"
CDS_SEC"1";
"B"
$PN"2"21;
"A"
$PN"1"5;
%"Q_RES"
"1","(-7225,2325)","0","pure_quanta","I38";
;
PART_NUMBER"CS-3302FB01"
VALUE"3.3"
WATTAGE"1/16W"
MATERIAL"CHIP"
TOLERANCE"1%"
PACK_TYPE"0402LF"
LOCATION"PR1801"
CDS_LIB"pure_quanta"
$SEC"1"
CDS_SEC"1";
"B"
$PN"2"36;
"A"
$PN"1"38;
%"Q_CAP"
"1","(-7525,2775)","0","pure_quanta","I39";
;
PART_NUMBER"CH5103KEB01"
TOLERANCE"10%"
VALUE"1UF"
VOLTAGE"16V"
PACK_TYPE"C0402"
MATERIAL"X6S"
LOCATION"PC400_P1_2"
CDS_LIB"pure_quanta"
LOCATION"PC400_P1_2"
$SEC"1"
CDS_SEC"1";
"B"
$PN"2"21;
"A"
$PN"1"5;
%"Q_CAP"
"1","(-7125,2775)","0","pure_quanta","I40";
;
PART_NUMBER"CH6223MEA01"
TOLERANCE"20%"
PACK_TYPE"C0805"
MATERIAL"X6S"
VALUE"22UF"
VOLTAGE"16V"
LOCATION"PC404_P1_2"
CDS_LIB"pure_quanta"
LOCATION"PC404_P1_2"
$SEC"1"
CDS_SEC"1";
"B"
$PN"2"21;
"A"
$PN"1"5;
%"Q_RES"
"1","(-6025,1625)","0","pure_quanta","I41";
;
PART_NUMBER"CS00002JB13"
WATTAGE"1/16W"
MATERIAL"CHIP"
TOLERANCE"5%"
PACK_TYPE"0402LF"
VALUE"0"
LOCATION"PR1332"
CDS_LIB"pure_quanta"
$SEC"1"
CDS_SEC"1";
"B"
$PN"2"7;
"A"
$PN"1"37;
%"Q_CAP"
"1","(-6725,2775)","0","pure_quanta","I42";
;
PART_NUMBER"CH6223MEA01"
TOLERANCE"20%"
MATERIAL"X6S"
VOLTAGE"16V"
VALUE"22UF"
PACK_TYPE"C0805"
LOCATION"PC406_P1_2"
CDS_LIB"pure_quanta"
LOCATION"PC406_P1_2"
$SEC"1"
CDS_SEC"1";
"B"
$PN"2"21;
"A"
$PN"1"5;
%"Q_CAP"
"1","(-6300,2150)","2","pure_quanta","I43";
;
PART_NUMBER"CH4106K1B01"
VALUE"100NF"
MATERIAL"X7R"
TOLERANCE"10%"
VOLTAGE"50V"
PACK_TYPE"C0402"
LOCATION"PC402"
CDS_LIB"pure_quanta"
$SEC"1"
CDS_SEC"1";
"B"
$PN"2"35;
"A"
$PN"1"36;
%"Q_INDUCTOR"
"1","(-6025,1900)","0","pure_quanta","I44";
;
PART_NUMBER"CV+13^0KZ11"
MATERIAL"IND"
PACK_TYPE"SMLF"
VALUE"130NH/106A"
LOCATION"PL19"
CDS_LIB"pure_quanta"
NEEDS_NO_SIZE"TRUE"
$SEC"1"
CDS_SEC"1";
"1"
$PN"1"34;
"2"
$PN"2"7;
%"UNIVERSAL_GND"
"1","(-6125,2400)","0","logical_power","I45";
;
HDL_POWER"GND"
CDS_LIB"logical_power";
"A"21;
%"Q_CAP"
"1","(-6275,2775)","0","pure_quanta","I46";
;
PART_NUMBER"CH6223MEA01"
TOLERANCE"20%"
PACK_TYPE"C0805"
VOLTAGE"16V"
MATERIAL"X6S"
VALUE"22UF"
LOCATION"PC725_P1_2"
CDS_LIB"pure_quanta"
$SEC"1"
CDS_SEC"1";
"B"
$PN"2"21;
"A"
$PN"1"5;
%"VCC15"
"1","(-6125,3150)","0","logical_power","I47";
;
HDL_POWER"SW_P12V_PVCCFA_EHV_FIVRA_CPU1_L"
CDS_LIB"logical_power";
"A"5;
%"UNIVERSAL_GND"
"1","(-8075,3950)","0","logical_power","I48";
;
HDL_POWER"GND"
CDS_LIB"logical_power";
"A"22;
%"Q_CAP"
"1","(-7925,5575)","0","pure_quanta","I49";
;
PART_NUMBER"TMP_QCH2336K1B12"
MATERIAL"X7R"
TOLERANCE"10%"
VALUE"3300PF"
VOLTAGE"50V"
PACK_TYPE"0402"
LOCATION"PC397_P1_1"
CDS_LIB"pure_quanta"
LOCATION"PC397_P1_1"
$SEC"1"
CDS_SEC"1";
"B"
$PN"2"23;
"A"
$PN"1"6;
%"Q_RES"
"1","(-7225,5125)","0","pure_quanta","I50";
;
PART_NUMBER"CS-3302FB01"
TOLERANCE"1%"
PACK_TYPE"0402LF"
WATTAGE"1/16W"
VALUE"3.3"
MATERIAL"CHIP"
LOCATION"PR1800"
CDS_LIB"pure_quanta"
$SEC"1"
CDS_SEC"1";
"B"
$PN"2"32;
"A"
$PN"1"33;
%"Q_CAP"
"1","(-7525,5575)","0","pure_quanta","I51";
;
PART_NUMBER"CH5103KEB01"
MATERIAL"X6S"
VALUE"1UF"
VOLTAGE"16V"
PACK_TYPE"C0402"
TOLERANCE"10%"
LOCATION"PC399_P1_1"
CDS_LIB"pure_quanta"
LOCATION"PC399_P1_1"
$SEC"1"
CDS_SEC"1";
"B"
$PN"2"23;
"A"
$PN"1"6;
%"Q_CAP"
"1","(-7125,5575)","0","pure_quanta","I52";
;
PART_NUMBER"CH6223MEA01"
TOLERANCE"20%"
MATERIAL"X6S"
PACK_TYPE"C0805"
VALUE"22UF"
VOLTAGE"16V"
LOCATION"PC403_P1_1"
CDS_LIB"pure_quanta"
LOCATION"PC403_P1_1"
$SEC"1"
CDS_SEC"1";
"B"
$PN"2"23;
"A"
$PN"1"6;
%"Q_RES"
"1","(-6025,4425)","0","pure_quanta","I53";
;
PART_NUMBER"CS00002JB13"
WATTAGE"1/16W"
TOLERANCE"5%"
VALUE"0"
PACK_TYPE"0402LF"
MATERIAL"CHIP"
LOCATION"PR1331"
CDS_LIB"pure_quanta"
$SEC"1"
CDS_SEC"1";
"B"
$PN"2"10;
"A"
$PN"1"31;
%"Q_CAP"
"1","(-6300,4950)","2","pure_quanta","I54";
;
PART_NUMBER"CH4106K1B01"
VALUE"100NF"
MATERIAL"X7R"
TOLERANCE"10%"
VOLTAGE"50V"
PACK_TYPE"C0402"
LOCATION"PC401"
CDS_LIB"pure_quanta"
$SEC"1"
CDS_SEC"1";
"B"
$PN"2"29;
"A"
$PN"1"32;
%"Q_INDUCTOR"
"1","(-6025,4700)","0","pure_quanta","I55";
;
PART_NUMBER"CV+13^0KZ11"
MATERIAL"IND"
PACK_TYPE"SMLF"
VALUE"130NH/106A"
LOCATION"PL18"
CDS_LIB"pure_quanta"
NEEDS_NO_SIZE"TRUE"
$SEC"1"
CDS_SEC"1";
"1"
$PN"1"30;
"2"
$PN"2"10;
%"Q_CAP"
"1","(-6725,5575)","0","pure_quanta","I56";
;
PART_NUMBER"CH6223MEA01"
TOLERANCE"20%"
VOLTAGE"16V"
PACK_TYPE"C0805"
VALUE"22UF"
MATERIAL"X6S"
LOCATION"PC405_P1_1"
CDS_LIB"pure_quanta"
LOCATION"PC405_P1_1"
$SEC"1"
CDS_SEC"1";
"B"
$PN"2"23;
"A"
$PN"1"6;
%"UNIVERSAL_GND"
"1","(-6125,5200)","0","logical_power","I57";
;
HDL_POWER"GND"
CDS_LIB"logical_power";
"A"23;
%"Q_CAP"
"1","(-6275,5575)","0","pure_quanta","I58";
;
PART_NUMBER"CH6223MEA01"
TOLERANCE"20%"
PACK_TYPE"C0805"
MATERIAL"X6S"
VALUE"22UF"
VOLTAGE"16V"
LOCATION"PC724_P1_1"
CDS_LIB"pure_quanta"
$SEC"1"
CDS_SEC"1";
"B"
$PN"2"23;
"A"
$PN"1"6;
%"VCC15"
"1","(-6125,5950)","0","logical_power","I59";
;
HDL_POWER"SW_P12V_PVCCFA_EHV_FIVRA_CPU1_R"
CDS_LIB"logical_power";
"A"6;
%"Q_CAP"
"1","(-5050,4475)","0","pure_quanta","I60";
;
PART_NUMBER"CH4106K1B01"
MATERIAL"X7R"
VOLTAGE"50V"
VALUE"100NF"
PACK_TYPE"C0402"
TOLERANCE"10%"
LOCATION"PC621_P1_1"
CDS_LIB"pure_quanta"
LOCATION"PC621_P1_1"
$SEC"1"
CDS_SEC"1";
"B"
$PN"2"27;
"A"
$PN"1"10;
%"Q_CAP"
"1","(-4975,1675)","0","pure_quanta","I61";
;
PART_NUMBER"CH5103KEB01"
MATERIAL"X6S"
TOLERANCE"10%"
VALUE"1UF"
VOLTAGE"16V"
PACK_TYPE"C0402"
LOCATION"PC408_P1_2"
CDS_LIB"pure_quanta"
LOCATION"PC408_P1_2"
$SEC"1"
CDS_SEC"1";
"B"
$PN"2"24;
"A"
$PN"1"7;
%"Q_CAP"
"1","(-4550,1675)","0","pure_quanta","I62";
;
PART_NUMBER"CH622KMEA03"
TOLERANCE"20%"
PACK_TYPE"C0805"
VOLTAGE"4V"
VALUE"22UF"
MATERIAL"X6S"
LOCATION"PC411_P1_2"
CDS_LIB"pure_quanta"
LOCATION"PC411_P1_2"
$SEC"1"
CDS_SEC"1";
"B"
$PN"2"24;
"A"
$PN"1"7;
%"Q_CAP"
"1","(-4125,1675)","0","pure_quanta","I63";
;
PART_NUMBER"CH622KMEA03"
TOLERANCE"20%"
PACK_TYPE"C0805"
VOLTAGE"4V"
MATERIAL"X6S"
VALUE"22UF"
LOCATION"PC413_P1_2"
CDS_LIB"pure_quanta"
LOCATION"PC413_P1_2"
$SEC"1"
CDS_SEC"1";
"B"
$PN"2"24;
"A"
$PN"1"7;
%"Q_RES"
"2","(-3650,1675)","0","pure_quanta","I64";
;
PART_NUMBER"CS14992FB06"
PACK_TYPE"0402LF"
MATERIAL"CHIP"
WATTAGE"1/16W"
TOLERANCE"1%"
VALUE"499"
LOCATION"PR4241"
BOM_COST"VR_PCH"
CDS_LIB"pure_quanta"
$SEC"1"
CDS_SEC"1";
"A"
$PN"1"7;
"B"
$PN"2"24;
%"UNIVERSAL_GND"
"1","(-3300,1325)","0","logical_power","I65";
;
HDL_POWER"GND"
CDS_LIB"logical_power";
"A"24;
%"Q_CAPP"
"1","(-4825,2800)","0","pure_quanta","I66";
;
PART_NUMBER"CC7560JMD16"
PACK_TYPE"THLF"
VALUE"560UF"
TOLERANCE"20%"
MATERIAL"OSCON"
VOLTAGE"2.5V"
LOCATION"PC414"
CDS_LIB"pure_quanta"
LOCATION"PC414"
$SEC"1"
CDS_SEC"1";
"A"
$PN"1"8;
"B"
$PN"2"25;
%"Q_CAPP"
"1","(-4300,2800)","0","pure_quanta","I67";
;
PART_NUMBER"CC7560JMD16"
PACK_TYPE"THLF"
VALUE"560UF"
TOLERANCE"20%"
MATERIAL"OSCON"
VOLTAGE"2.5V"
LOCATION"PC415"
CDS_LIB"pure_quanta"
LOCATION"PC415"
$SEC"1"
CDS_SEC"1";
"A"
$PN"1"8;
"B"
$PN"2"25;
%"Q_CAPP"
"1","(-3775,2800)","0","pure_quanta","I68";
;
PART_NUMBER"CC7560JMD16"
PACK_TYPE"THLF"
VALUE"560UF"
TOLERANCE"20%"
MATERIAL"OSCON"
VOLTAGE"2.5V"
LOCATION"PC416"
CDS_LIB"pure_quanta"
LOCATION"PC416"
$SEC"1"
CDS_SEC"1";
"A"
$PN"1"8;
"B"
$PN"2"25;
%"VCC15"
"1","(-3300,2000)","0","logical_power","I69";
;
HDL_POWER"PVCCFA_EHV_FIVRA_CPU1"
CDS_LIB"logical_power";
"A"7;
%"Q_CAPP"
"1","(-3275,2800)","0","pure_quanta","I70";
;
PART_NUMBER"CH733LY8802"
VOLTAGE"2.5V"
VALUE"330UF"
MATERIAL"SPCAP"
PACK_TYPE"SMLF"
TOLERANCE"+10/-35%"
LOCATION"PC418"
CDS_LIB"pure_quanta"
LOCATION"PC418"
$SEC"1"
CDS_SEC"1";
"A"
$PN"1"8;
"B"
$PN"2"25;
%"UNIVERSAL_GND"
"1","(-2825,2450)","0","logical_power","I71";
;
HDL_POWER"GND"
CDS_LIB"logical_power";
"A"25;
%"Q_CAPP"
"1","(-2825,2800)","0","pure_quanta","I72";
;
PART_NUMBER"CH733LY8802"
VOLTAGE"2.5V"
MATERIAL"SPCAP"
PACK_TYPE"SMLF"
VALUE"330UF"
TOLERANCE"+10/-35%"
LOCATION"PC2172"
CDS_LIB"pure_quanta"
$SEC"1"
CDS_SEC"1";
"A"
$PN"1"8;
"B"
$PN"2"25;
%"VCC15"
"1","(-2825,3125)","0","logical_power","I73";
;
HDL_POWER"PVCCFA_EHV_FIVRA_CPU1"
CDS_LIB"logical_power";
"A"8;
%"Q_CAP"
"1","(-4550,4475)","0","pure_quanta","I74";
;
PART_NUMBER"CH622KMEA03"
TOLERANCE"20%"
PACK_TYPE"C0805"
VOLTAGE"4V"
VALUE"22UF"
MATERIAL"X6S"
LOCATION"PC410_P1_1"
CDS_LIB"pure_quanta"
LOCATION"PC410_P1_1"
$SEC"1"
CDS_SEC"1";
"B"
$PN"2"27;
"A"
$PN"1"10;
%"Q_CAP"
"1","(-4125,4475)","0","pure_quanta","I75";
;
PART_NUMBER"CH622KMEA03"
TOLERANCE"20%"
PACK_TYPE"C0805"
VOLTAGE"4V"
MATERIAL"X6S"
VALUE"22UF"
LOCATION"PC412_P1_1"
CDS_LIB"pure_quanta"
LOCATION"PC412_P1_1"
$SEC"1"
CDS_SEC"1";
"B"
$PN"2"27;
"A"
$PN"1"10;
%"GND"
"1","(-5000,5100)","0","logical_power","I76";
;
HDL_POWER"GND"
CDS_LIB"logical_power"
SIZE"1B";
"A<SIZE-1..0>\NAC"26;
%"Q_CAP"
"1","(-5000,5350)","0","pure_quanta","I77";
;
PART_NUMBER"CH4106K1B01"
PACK_TYPE"C0402"
VOLTAGE"50V"
VALUE"100NF"
TOLERANCE"10%"
MATERIAL"X7R"
LOCATION"PC1657"
CDS_LIB"pure_quanta"
$SEC"1"
CDS_SEC"1";
"B"
$PN"2"26;
"A"
$PN"1"9;
%"VCC15"
"1","(-5000,5725)","0","logical_power","I78";
;
HDL_POWER"P12V_AUX"
CDS_LIB"logical_power";
"A"9;
%"Q_INDUCTOR"
"1","(-4575,5575)","0","pure_quanta","I79";
;
PART_NUMBER"CV+10G0MZ04"
VALUE"100NH/16A"
MATERIAL"IND"
PACK_TYPE"SMLF"
LOCATION"PL43"
CDS_LIB"pure_quanta"
NEEDS_NO_SIZE"TRUE"
$SEC"1"
CDS_SEC"1";
"1"
$PN"1"9;
"2"
$PN"2"11;
%"Q_CAP"
"2","(-9975,1675)","0","pure_quanta","I8";
;
PART_NUMBER"CH4104K1B00"
MATERIAL"X7R"
PACK_TYPE"0402"
TOLERANCE"10%"
VOLTAGE"25V"
VALUE"0.1UF"
LOCATION"PC1368"
CDS_LIB"pure_quanta"
$SEC"1"
CDS_SEC"1";
"A"
$PN"1"13;
"B"
$PN"2"49;
%"Q_CAP"
"1","(-4250,5325)","0","pure_quanta","I80";
;
PART_NUMBER"CH6223MEA01"
TOLERANCE"20%"
VALUE"22UF"
VOLTAGE"16V"
MATERIAL"X6S"
PACK_TYPE"C0805"
LOCATION"PC1677"
CDS_LIB"pure_quanta"
$SEC"1"
CDS_SEC"1";
"B"
$PN"2"28;
"A"
$PN"1"11;
%"UNIVERSAL_GND"
"1","(-3825,4100)","0","logical_power","I81";
;
HDL_POWER"GND"
CDS_LIB"logical_power";
"A"27;
%"VCC15"
"1","(-3825,4875)","0","logical_power","I82";
;
HDL_POWER"PVCCFA_EHV_FIVRA_CPU1"
CDS_LIB"logical_power";
"A"10;
%"Q_CAP"
"1","(-3950,5325)","0","pure_quanta","I83";
;
PART_NUMBER"CH6223MEA01"
TOLERANCE"20%"
MATERIAL"X6S"
PACK_TYPE"C0805"
VALUE"22UF"
VOLTAGE"16V"
LOCATION"PC1678"
CDS_LIB"pure_quanta"
$SEC"1"
CDS_SEC"1";
"B"
$PN"2"28;
"A"
$PN"1"11;
%"Q_CAP"
"1","(-3675,5325)","0","pure_quanta","I84";
;
PART_NUMBER"CH6223MEA01"
TOLERANCE"20%"
PACK_TYPE"C0805"
MATERIAL"X6S"
VOLTAGE"16V"
VALUE"22UF"
LOCATION"PC1679"
CDS_LIB"pure_quanta"
$SEC"1"
CDS_SEC"1";
"B"
$PN"2"28;
"A"
$PN"1"11;
%"Q_CAP"
"1","(-3400,5325)","0","pure_quanta","I85";
;
PART_NUMBER"CH6223MEA01"
TOLERANCE"20%"
VOLTAGE"16V"
VALUE"22UF"
MATERIAL"X6S"
PACK_TYPE"C0805"
LOCATION"PC1680"
CDS_LIB"pure_quanta"
$SEC"1"
CDS_SEC"1";
"B"
$PN"2"28;
"A"
$PN"1"11;
%"UNIVERSAL_GND"
"1","(-3125,5025)","0","logical_power","I86";
;
HDL_POWER"GND"
CDS_LIB"logical_power";
"A"28;
%"Q_CAPP"
"1","(-3125,5325)","0","pure_quanta","I87";
;
PART_NUMBER"CC72703MD38"
PACK_TYPE"THLF"
TOLERANCE"20%"
MATERIAL"OSCON"
VALUE"270UF"
VOLTAGE"16V"
LOCATION"PC417"
CDS_LIB"pure_quanta"
LOCATION"PC417"
$SEC"1"
CDS_SEC"1";
"A"
$PN"1"11;
"B"
$PN"2"28;
%"VCC15"
"1","(-2975,5700)","0","logical_power","I88";
;
HDL_POWER"SW_P12V_PVCCFA_EHV_FIVRA_CPU1_L"
CDS_LIB"logical_power";
"A"11;
%"ISL99390FRZTR5935"
"1","(-8725,4675)","0","pure_quanta","I89";
;
PART_NUMBER"AL099390004"
PART_TYPE"SMLF"
VALUE"ISL99390FRZ-TR5935"
MATERIAL"IC"
LOCATION"PU75_P1_1"
CDS_LIB"pure_quanta"
CDS_LMAN_SYM_OUTLINE"-300,700,250,-650"
NEEDS_NO_SIZE"TRUE"
$SEC"1"
CDS_SEC"1";
"PGND2"
$PN"7_9-20_24"22;
"GL2"
$PN"41"0;
"GL1"
$PN"6"0;
"DNC"
$PN"31"0;
"EN"
$PN"35"40;
"PGND3"
$PN"40"22;
"VOS"
$PN"1"31;
"VIN2"
$PN"30"6;
"PGND1"
$PN"5"22;
"SW"
$PN"10_19"30;
"LSET"
$PN"37"45;
"IOUT"
$PN"38"44;
"TOUT_FLT"
$PN"36"42;
"PVCC"
$PN"4"39;
"PHASE"
$PN"32"29;
"VIN1"
$PN"25_29"6;
"BOOT"
$PN"33"33;
"AGND"
$PN"2"22;
"VCC"
$PN"3"40;
"REFIN"
$PN"39"41;
"PWM"
$PN"34"43;
%"ISL99390FRZTR5935"
"1","(-8725,1875)","0","pure_quanta","I9";
;
PART_NUMBER"AL099390004"
MATERIAL"IC"
PART_TYPE"SMLF"
VALUE"ISL99390FRZ-TR5935"
LOCATION"PU76_P1_2"
CDS_LIB"pure_quanta"
CDS_LMAN_SYM_OUTLINE"-300,700,250,-650"
NEEDS_NO_SIZE"TRUE"
$SEC"1"
CDS_SEC"1";
"PGND2"
$PN"7_9-20_24"20;
"GL2"
$PN"41"0;
"GL1"
$PN"6"0;
"DNC"
$PN"31"0;
"EN"
$PN"35"47;
"PGND3"
$PN"40"20;
"VOS"
$PN"1"37;
"VIN2"
$PN"30"5;
"PGND1"
$PN"5"20;
"SW"
$PN"10_19"34;
"LSET"
$PN"37"52;
"IOUT"
$PN"38"48;
"TOUT_FLT"
$PN"36"51;
"PVCC"
$PN"4"46;
"PHASE"
$PN"32"35;
"VIN1"
$PN"25_29"5;
"BOOT"
$PN"33"38;
"AGND"
$PN"2"20;
"VCC"
$PN"3"47;
"REFIN"
$PN"39"49;
"PWM"
$PN"34"50;
END.
